# T6G (Grand Teton) — schematic netlist excerpt (pin names and nets, part order shuffled) for the footprints in the layout excerpt that follows; sources: Cadence DE-HDL packaged netlist, KiCad conversion of 04192023_DAF0TMB3IC0_F0TG_MB_C_brd_V02_OCP.brd

R3672  Q_RES  0 5% CHIP  pkg 0402LF  page 257 : A = SMB_SCM_2_R4_SCL ; B = SMB_SEN_TIC_3V3AUX_SCL

(kicad_pcb
	(version 20260206)
	(generator "pcbnew")
	(generator_version "10.0")
	(general
		(thickness 1.6)
		(legacy_teardrops no)
	)
	(paper "A4")
	(title_block
		(title "04192023_DAF0TMB3IC0_F0TG_MB_C_brd_V02_OCP.brd")
		(comment 1 "Grand Teton / footprints 3354-3354 of 8354")
	)
	(layers
		(0 "F.Cu" signal "TOP")
		(4 "In1.Cu" signal "GND")
		(6 "In2.Cu" signal "IN1")
		(8 "In3.Cu" signal "GND1")
		(10 "In4.Cu" signal "IN2")
		(12 "In5.Cu" signal "GND2")
		(14 "In6.Cu" signal "IN3")
		(16 "In7.Cu" signal "GND3")
		(18 "In8.Cu" signal "VCC")
		(20 "In9.Cu" signal "VCC1")
		(22 "In10.Cu" signal "GND4")
		(24 "In11.Cu" signal "IN4")
		(26 "In12.Cu" signal "GND5")
		(28 "In13.Cu" signal "IN5")
		(30 "In14.Cu" signal "GND6")
		(32 "In15.Cu" signal "IN6")
		(34 "In16.Cu" signal "GND7")
		(2 "B.Cu" signal "BOTTOM")
		(9 "F.Adhes" user "F.Adhesive")
		(11 "B.Adhes" user "B.Adhesive")
		(13 "F.Paste" user "Package Geometry/Pastemask Top")
		(15 "B.Paste" user "Package Geometry/Pastemask Bottom")
		(5 "F.SilkS" user "Ref Des/Silkscreen Top")
		(7 "B.SilkS" user "Ref Des/Silkscreen Bottom")
		(1 "F.Mask" user "Board Geometry/Soldermask Top")
		(3 "B.Mask" user "Board Geometry/Soldermask Bottom")
		(17 "Dwgs.User" user "User.Drawings")
		(19 "Cmts.User" user "User.Comments")
		(21 "Eco1.User" user "User.Eco1")
		(23 "Eco2.User" user "User.Eco2")
		(25 "Edge.Cuts" user "Board Geometry/Outline")
		(27 "Margin" user)
		(31 "F.CrtYd" user "Package Geometry/Place Bound Top")
		(29 "B.CrtYd" user "Package Geometry/Place Bound Bottom")
		(35 "F.Fab" user "Ref Des/Assembly Top")
		(33 "B.Fab" user "Ref Des/Assembly Bottom")
	)
	(footprint ""
		(layer "F.Cu")
		(at 305.819048 -45.005498)
		(property "Reference" "R3672"
			(at 0 0 0)
			(layer "F.SilkS")
			(hide yes)
			(effects
				(font
					(size 1.27 1.27)
				)
			)
		)
		(property "Value" ""
			(at 0 0 0)
			(layer "F.Fab")
			(effects
				(font
					(size 1.27 1.27)
				)
			)
		)
		(duplicate_pad_numbers_are_jumpers no)
		(fp_line
			(start -0.7874 -0.4064)
			(end 0.7874 -0.4064)
			(stroke
				(width 0.1524)
				(type default)
			)
			(layer "F.SilkS")
		)
		(fp_line
			(start -0.7874 0.4064)
			(end -0.7874 -0.4064)
			(stroke
				(width 0.1524)
				(type default)
			)
			(layer "F.SilkS")
		)
		(fp_line
			(start 0.7874 -0.4064)
			(end 0.7874 0.4064)
			(stroke
				(width 0.1524)
				(type default)
			)
			(layer "F.SilkS")
		)
		(fp_line
			(start 0.7874 0.4064)
			(end -0.7874 0.4064)
			(stroke
				(width 0.1524)
				(type default)
			)
			(layer "F.SilkS")
		)
		(fp_line
			(start -0.67945 -0.305054)
			(end -0.12065 -0.305054)
			(stroke
				(width 0.1)
				(type default)
			)
			(layer "F.Fab")
		)
		(fp_line
			(start -0.67945 0.3048)
			(end -0.67945 -0.305054)
			(stroke
				(width 0.1)
				(type default)
			)
			(layer "F.Fab")
		)
		(fp_line
			(start -0.12065 -0.305054)
			(end -0.12065 -0.2794)
			(stroke
				(width 0.1)
				(type default)
			)
			(layer "F.Fab")
		)
		(fp_line
			(start -0.12065 -0.2794)
			(end 0.12065 -0.2794)
			(stroke
				(width 0.1)
				(type default)
			)
			(layer "F.Fab")
		)
		(fp_line
			(start -0.12065 0.2794)
			(end -0.12065 0.3048)
			(stroke
				(width 0.1)
				(type default)
			)
			(layer "F.Fab")
		)
		(fp_line
			(start -0.12065 0.3048)
			(end -0.67945 0.3048)
			(stroke
				(width 0.1)
				(type default)
			)
			(layer "F.Fab")
		)
		(fp_line
			(start 0.120396 0.2794)
			(end -0.12065 0.2794)
			(stroke
				(width 0.1)
				(type default)
			)
			(layer "F.Fab")
		)
		(fp_line
			(start 0.120396 0.3048)
			(end 0.120396 0.2794)
			(stroke
				(width 0.1)
				(type default)
			)
			(layer "F.Fab")
		)
		(fp_line
			(start 0.12065 -0.3048)
			(end 0.67945 -0.3048)
			(stroke
				(width 0.1)
				(type default)
			)
			(layer "F.Fab")
		)
		(fp_line
			(start 0.12065 -0.2794)
			(end 0.12065 -0.3048)
			(stroke
				(width 0.1)
				(type default)
			)
			(layer "F.Fab")
		)
		(fp_line
			(start 0.67945 -0.3048)
			(end 0.67945 0.3048)
			(stroke
				(width 0.1)
				(type default)
			)
			(layer "F.Fab")
		)
		(fp_line
			(start 0.67945 0.3048)
			(end 0.120396 0.3048)
			(stroke
				(width 0.1)
				(type default)
			)
			(layer "F.Fab")
		)
		(pad "1" smd circle
			(at -0.40005 0)
			(size 0 0)
			(layers "F.Cu" "F.Mask" "F.Paste")
			(net "SMB_SCM_2_R4_SCL")
		)
		(pad "2" smd circle
			(at 0.40005 0)
			(size 0 0)
			(layers "F.Cu" "F.Mask" "F.Paste")
			(net "SMB_SEN_TIC_3V3AUX_SCL")
		)
	)
)
